(kicad_pcb
	(version 20241229)
	(generator "pcbnew")
	(generator_version "9.0")
	(general
		(thickness 1.6)
		(legacy_teardrops no)
	)
	(paper "A4")
	(title_block
		(title "GMSL Deserializer")
		(date "2025-10-09")
		(rev "1.0.4")
		(company "Antmicro Ltd")
		(comment 1 "www.antmicro.com")
		(comment 9 "footprints 85-90 of 235")
	)
	(layers
		(0 "F.Cu" signal)
		(4 "In1.Cu" power)
		(6 "In2.Cu" power)
		(2 "B.Cu" signal)
		(9 "F.Adhes" user "F.Adhesive")
		(11 "B.Adhes" user "B.Adhesive")
		(13 "F.Paste" user)
		(15 "B.Paste" user)
		(5 "F.SilkS" user "F.Silkscreen")
		(7 "B.SilkS" user "B.Silkscreen")
		(1 "F.Mask" user)
		(3 "B.Mask" user)
		(17 "Dwgs.User" user "User.Drawings")
		(19 "Cmts.User" user "User.Comments")
		(21 "Eco1.User" user "User.Eco1")
		(23 "Eco2.User" user "User.Eco2")
		(25 "Edge.Cuts" user)
		(27 "Margin" user)
		(31 "F.CrtYd" user "F.Courtyard")
		(29 "B.CrtYd" user "B.Courtyard")
		(35 "F.Fab" user)
		(33 "B.Fab" user)
	)
	(footprint "antmicro-footprints:R_0402_1005Metric"
		(layer "F.Cu")
		(at 139.192 56.642 90)
		(descr "Resistor SMD 0402")
		(tags "resistor SMD 0402")
		(property "Reference" "R25"
			(at -1.122484 1.262 90)
			(layer "F.SilkS")
			(effects
				(font
					(size 0.7 0.7)
					(thickness 0.15)
				)
				(justify left bottom)
			)
		)
		(property "Value" "R_5k1_0402"
			(at -1.011843 1.772047 90)
			(layer "F.Fab")
			(effects
				(font
					(size 0.7 0.7)
					(thickness 0.15)
				)
				(justify left bottom)
			)
		)
		(property "Datasheet" "https://www.bourns.com/docs/product-datasheets/cr.pdf"
			(at 0 0 90)
			(layer "F.Fab")
			(hide yes)
			(effects
				(font
					(size 1.27 1.27)
					(thickness 0.15)
				)
			)
		)
		(property "Description" "SMD Chip Resistor, 5.1 kohm, ± 1%, 63 mW, 0402 [1005 Metric], Thick Film, General Purpose"
			(at 0 0 90)
			(layer "F.Fab")
			(hide yes)
			(effects
				(font
					(size 1.27 1.27)
					(thickness 0.15)
				)
			)
		)
		(property "Author" "Antmicro"
			(at 195.834 -82.55 0)
			(layer "F.Fab")
			(hide yes)
			(effects
				(font
					(size 1 1)
					(thickness 0.15)
				)
			)
		)
		(property "License" "Apache-2.0"
			(at 195.834 -82.55 0)
			(layer "F.Fab")
			(hide yes)
			(effects
				(font
					(size 1 1)
					(thickness 0.15)
				)
			)
		)
		(property "MPN" "CR0402-FX-5101GLF"
			(at 195.834 -82.55 0)
			(layer "F.Fab")
			(hide yes)
			(effects
				(font
					(size 1 1)
					(thickness 0.15)
				)
			)
		)
		(property "Manufacturer" "Bourns"
			(at 195.834 -82.55 0)
			(layer "F.Fab")
			(hide yes)
			(effects
				(font
					(size 1 1)
					(thickness 0.15)
				)
			)
		)
		(property "Tolerance" "1%"
			(at 195.834 -82.55 0)
			(layer "F.Fab")
			(hide yes)
			(effects
				(font
					(size 1 1)
					(thickness 0.15)
				)
			)
		)
		(property "Val" "5k1"
			(at 195.834 -82.55 0)
			(layer "F.Fab")
			(hide yes)
			(effects
				(font
					(size 1 1)
					(thickness 0.15)
				)
			)
		)
		(sheetname "/Power/")
		(sheetfile "power.kicad_sch")
		(attr smd)
		(fp_rect
			(start -0.925 -0.47)
			(end 0.925 0.47)
			(stroke
				(width 0.05)
				(type default)
			)
			(fill no)
			(layer "F.CrtYd")
		)
		(fp_rect
			(start -0.5 -0.25)
			(end 0.5 0.25)
			(stroke
				(width 0.15)
				(type solid)
			)
			(fill no)
			(layer "F.Fab")
		)
		(pad "1" smd roundrect
			(at -0.48 0 90)
			(size 0.59 0.64)
			(layers "F.Cu" "F.Mask" "F.Paste")
			(roundrect_rratio 0.25)
			(net 52 "Net-(L2-Pad2)")
			(pintype "passive")
		)
		(pad "2" smd roundrect
			(at 0.48 0 90)
			(size 0.59 0.64)
			(layers "F.Cu" "F.Mask" "F.Paste")
			(roundrect_rratio 0.25)
			(net 56 "Net-(L10-Pad1)")
			(pintype "passive")
		)
	)
	(footprint "antmicro-footprints:L_Coilcraft-MSS6132T"
		(layer "F.Cu")
		(at 146.558 61.976 90)
		(property "Reference" "L3"
			(at -0.635 -3.429 90)
			(layer "F.SilkS")
			(effects
				(font
					(size 0.7 0.7)
					(thickness 0.15)
				)
				(justify left bottom)
			)
		)
		(property "Value" "L_22u_1.12A_Coilcraft-MSS6132T"
			(at -0.508 4.826 90)
			(layer "F.Fab")
			(effects
				(font
					(size 0.7 0.7)
					(thickness 0.15)
				)
				(justify left bottom)
			)
		)
		(property "Datasheet" "https://www.coilcraft.com/getmedia/d035c9b3-191d-46aa-ab3f-5c1a849157c1/mss6132t.pdf"
			(at 0 0 90)
			(layer "F.Fab")
			(hide yes)
			(effects
				(font
					(size 1.27 1.27)
					(thickness 0.15)
				)
			)
		)
		(property "Description" "Power Inductor (SMT), 22 µH, 1.85 A, Shielded, 2.45 A, WE-MAPI"
			(at 0 0 90)
			(layer "F.Fab")
			(hide yes)
			(effects
				(font
					(size 1.27 1.27)
					(thickness 0.15)
				)
			)
		)
		(property "Author" "Antmicro"
			(at 208.534 -84.582 0)
			(layer "F.Fab")
			(hide yes)
			(effects
				(font
					(size 1 1)
					(thickness 0.15)
				)
			)
		)
		(property "IMax" "1.45A"
			(at 208.534 -84.582 0)
			(layer "F.Fab")
			(hide yes)
			(effects
				(font
					(size 1 1)
					(thickness 0.15)
				)
			)
		)
		(property "ISat" "1.12A"
			(at 208.534 -84.582 0)
			(layer "F.Fab")
			(hide yes)
			(effects
				(font
					(size 1 1)
					(thickness 0.15)
				)
			)
		)
		(property "License" "Apache-2.0"
			(at 208.534 -84.582 0)
			(layer "F.Fab")
			(hide yes)
			(effects
				(font
					(size 1 1)
					(thickness 0.15)
				)
			)
		)
		(property "MPN" "MSS6132T-223"
			(at 208.534 -84.582 0)
			(layer "F.Fab")
			(hide yes)
			(effects
				(font
					(size 1 1)
					(thickness 0.15)
				)
			)
		)
		(property "Manufacturer" "Coilcraft"
			(at 208.534 -84.582 0)
			(layer "F.Fab")
			(hide yes)
			(effects
				(font
					(size 1 1)
					(thickness 0.15)
				)
			)
		)
		(property "Size" "6.1x6.1"
			(at 208.534 -84.582 0)
			(layer "F.Fab")
			(hide yes)
			(effects
				(font
					(size 1 1)
					(thickness 0.15)
				)
			)
		)
		(property "Val" "22u/1.12A"
			(at 208.534 -84.582 0)
			(layer "F.Fab")
			(hide yes)
			(effects
				(font
					(size 1 1)
					(thickness 0.15)
				)
			)
		)
		(sheetname "/Power/")
		(sheetfile "power.kicad_sch")
		(attr smd)
		(fp_line
			(start -0.8 -3.05)
			(end 0.8 -3.05)
			(stroke
				(width 0.15)
				(type solid)
			)
			(layer "F.SilkS")
		)
		(fp_line
			(start -0.8 3.05)
			(end 0.8 3.05)
			(stroke
				(width 0.15)
				(type solid)
			)
			(layer "F.SilkS")
		)
		(fp_rect
			(start -3.35 -3.35)
			(end 3.35 3.35)
			(stroke
				(width 0.05)
				(type solid)
			)
			(fill no)
			(layer "F.CrtYd")
		)
		(fp_rect
			(start -3.1 -3.1)
			(end 3.1 3.1)
			(stroke
				(width 0.15)
				(type solid)
			)
			(fill no)
			(layer "F.Fab")
		)
		(pad "1" smd custom
			(at -2.71 0 180)
			(size 6 0.575)
			(layers "F.Cu" "F.Mask" "F.Paste")
			(net 4 "+12V")
			(pintype "passive")
			(options
				(clearance outline)
				(anchor rect)
			)
			(primitives
				(gr_poly
					(pts
						(xy 2.4 1.71) (xy 2.117646 1.21) (xy 1.9 0.96) (xy 1.65 0.71) (xy 1.2 0.41) (xy 0.4 0.11) (xy 0.4 0.01)
						(xy 2.9 0) (xy 2.9 1.71)
					)
					(width 0.2)
					(fill yes)
				)
				(gr_poly
					(pts
						(xy -2.4 1.731128) (xy -2.117646 1.231128) (xy -1.9 0.981128) (xy -1.65 0.731128) (xy -1.2 0.431128)
						(xy -0.4 0.131128) (xy -0.4 0.031128) (xy -2.9 0.021128) (xy -2.9 1.731128)
					)
					(width 0.2)
					(fill yes)
				)
			)
		)
		(pad "2" smd custom
			(at 2.71 0)
			(size 6 0.575)
			(layers "F.Cu" "F.Mask" "F.Paste")
			(net 53 "Net-(L3-Pad2)")
			(pintype "passive")
			(options
				(clearance outline)
				(anchor rect)
			)
			(primitives
				(gr_poly
					(pts
						(xy -2.4 1.731128) (xy -2.117646 1.231128) (xy -1.9 0.981128) (xy -1.65 0.731128) (xy -1.2 0.431128)
						(xy -0.4 0.131128) (xy -0.4 0.031128) (xy -2.9 0.021128) (xy -2.9 1.731128)
					)
					(width 0.2)
					(fill yes)
				)
				(gr_poly
					(pts
						(xy 2.4 1.71) (xy 2.117646 1.21) (xy 1.9 0.96) (xy 1.65 0.71) (xy 1.2 0.41) (xy 0.4 0.11) (xy 0.4 0.01)
						(xy 2.9 0) (xy 2.9 1.71)
					)
					(width 0.2)
					(fill yes)
				)
			)
		)
	)
	(footprint "antmicro-footprints:TP_SMD_0.75mm"
		(layer "F.Cu")
		(at 149.352 97.89)
		(property "Reference" "TP10"
			(at 0 -0.6 0)
			(layer "F.SilkS")
			(hide yes)
			(effects
				(font
					(size 0.7 0.7)
					(thickness 0.15)
				)
				(justify left bottom)
			)
		)
		(property "Value" "TP_0.75mm_SMD"
			(at 0 1.2 0)
			(layer "F.Fab")
			(effects
				(font
					(size 0.7 0.7)
					(thickness 0.15)
				)
				(justify left bottom)
			)
		)
		(property "Description" "SMT test point"
			(at 0 0 0)
			(layer "F.Fab")
			(hide yes)
			(effects
				(font
					(size 1.27 1.27)
					(thickness 0.15)
				)
			)
		)
		(property "Author" "Antmicro"
			(at 0 0 0)
			(layer "F.Fab")
			(hide yes)
			(effects
				(font
					(size 1 1)
					(thickness 0.15)
				)
			)
		)
		(property "License" "Apache-2.0"
			(at 0 0 0)
			(layer "F.Fab")
			(hide yes)
			(effects
				(font
					(size 1 1)
					(thickness 0.15)
				)
			)
		)
		(property "MPN" ""
			(at 0 0 0)
			(layer "F.Fab")
			(hide yes)
			(effects
				(font
					(size 1 1)
					(thickness 0.15)
				)
			)
		)
		(property "Manufacturer" ""
			(at 0 0 0)
			(layer "F.Fab")
			(hide yes)
			(effects
				(font
					(size 1 1)
					(thickness 0.15)
				)
			)
		)
		(sheetname "/Power/")
		(sheetfile "power.kicad_sch")
		(fp_circle
			(center 0 0)
			(end 0.475 0)
			(stroke
				(width 0.05)
				(type default)
			)
			(fill no)
			(layer "F.CrtYd")
		)
		(pad "1" smd circle
			(at 0 0)
			(size 0.75 0.75)
			(layers "F.Cu" "F.Mask")
			(net 4 "+12V")
			(pinfunction "1")
			(pintype "passive")
		)
	)
	(footprint "antmicro-footprints:C_0402_1005Metric"
		(layer "F.Cu")
		(at 134.294 66.548 90)
		(descr "Capacitor SMD 0402")
		(tags "capacitor SMD 0402")
		(property "Reference" "C7"
			(at -1.397 -0.563 90)
			(layer "F.SilkS")
			(effects
				(font
					(size 0.7 0.7)
					(thickness 0.15)
				)
				(justify left bottom)
			)
		)
		(property "Value" "C_100n_0402"
			(at -1.022927 2.155213 90)
			(layer "F.Fab")
			(effects
				(font
					(size 0.7 0.7)
					(thickness 0.15)
				)
				(justify left bottom)
			)
		)
		(property "Datasheet" "https://www.murata.com/products/productdetail?partno=GRM155R61H104KE14%23"
			(at 0 0 90)
			(layer "F.Fab")
			(hide yes)
			(effects
				(font
					(size 1.27 1.27)
					(thickness 0.15)
				)
			)
		)
		(property "Description" "SMD Multilayer Ceramic Capacitor, 0.1 µF, 50 V, 0402 [1005 Metric], ± 10%, X5R, GRM Series"
			(at 0 0 90)
			(layer "F.Fab")
			(hide yes)
			(effects
				(font
					(size 1.27 1.27)
					(thickness 0.15)
				)
			)
		)
		(property "Author" "Antmicro"
			(at 200.842 -67.746 0)
			(layer "F.Fab")
			(hide yes)
			(effects
				(font
					(size 1 1)
					(thickness 0.15)
				)
			)
		)
		(property "Dielectric" "X5R"
			(at 200.842 -67.746 0)
			(layer "F.Fab")
			(hide yes)
			(effects
				(font
					(size 1 1)
					(thickness 0.15)
				)
			)
		)
		(property "License" "Apache-2.0"
			(at 200.842 -67.746 0)
			(layer "F.Fab")
			(hide yes)
			(effects
				(font
					(size 1 1)
					(thickness 0.15)
				)
			)
		)
		(property "MPN" "GRM155R61H104KE14D"
			(at 200.842 -67.746 0)
			(layer "F.Fab")
			(hide yes)
			(effects
				(font
					(size 1 1)
					(thickness 0.15)
				)
			)
		)
		(property "Manufacturer" "Murata"
			(at 200.842 -67.746 0)
			(layer "F.Fab")
			(hide yes)
			(effects
				(font
					(size 1 1)
					(thickness 0.15)
				)
			)
		)
		(property "Val" "100n"
			(at 200.842 -67.746 0)
			(layer "F.Fab")
			(hide yes)
			(effects
				(font
					(size 1 1)
					(thickness 0.15)
				)
			)
		)
		(property "Voltage" "50V"
			(at 200.842 -67.746 0)
			(layer "F.Fab")
			(hide yes)
			(effects
				(font
					(size 1 1)
					(thickness 0.15)
				)
			)
		)
		(sheetname "/Power/")
		(sheetfile "power.kicad_sch")
		(attr smd)
		(fp_rect
			(start -0.925 -0.47)
			(end 0.925 0.47)
			(stroke
				(width 0.05)
				(type default)
			)
			(fill no)
			(layer "F.CrtYd")
		)
		(fp_line
			(start 0.504 -0.25)
			(end 0.504 0.248)
			(stroke
				(width 0.15)
				(type solid)
			)
			(layer "F.Fab")
		)
		(fp_line
			(start -0.494 -0.25)
			(end 0.504 -0.25)
			(stroke
				(width 0.15)
				(type solid)
			)
			(layer "F.Fab")
		)
		(fp_line
			(start 0.504 0.248)
			(end -0.494 0.248)
			(stroke
				(width 0.15)
				(type solid)
			)
			(layer "F.Fab")
		)
		(fp_line
			(start -0.494 0.248)
			(end -0.494 -0.25)
			(stroke
				(width 0.15)
				(type solid)
			)
			(layer "F.Fab")
		)
		(pad "1" smd roundrect
			(at -0.48 0 90)
			(size 0.59 0.64)
			(layers "F.Cu" "F.Mask" "F.Paste")
			(roundrect_rratio 0.25)
			(net 1 "GND")
			(pintype "passive")
		)
		(pad "2" smd roundrect
			(at 0.48 0 90)
			(size 0.59 0.64)
			(layers "F.Cu" "F.Mask" "F.Paste")
			(roundrect_rratio 0.25)
			(net 4 "+12V")
			(pintype "passive")
		)
	)
	(footprint "antmicro-footprints:R_0402_1005Metric"
		(layer "F.Cu")
		(at 150.614 61.976 90)
		(descr "Resistor SMD 0402")
		(tags "resistor SMD 0402")
		(property "Reference" "R21"
			(at -1.1405 1.27 90)
			(layer "F.SilkS")
			(effects
				(font
					(size 0.7 0.7)
					(thickness 0.15)
				)
				(justify left bottom)
			)
		)
		(property "Value" "R_5k1_0402"
			(at -1.011843 1.772047 90)
			(layer "F.Fab")
			(effects
				(font
					(size 0.7 0.7)
					(thickness 0.15)
				)
				(justify left bottom)
			)
		)
		(property "Datasheet" "https://www.bourns.com/docs/product-datasheets/cr.pdf"
			(at 0 0 90)
			(layer "F.Fab")
			(hide yes)
			(effects
				(font
					(size 1.27 1.27)
					(thickness 0.15)
				)
			)
		)
		(property "Description" "SMD Chip Resistor, 5.1 kohm, ± 1%, 63 mW, 0402 [1005 Metric], Thick Film, General Purpose"
			(at 0 0 90)
			(layer "F.Fab")
			(hide yes)
			(effects
				(font
					(size 1.27 1.27)
					(thickness 0.15)
				)
			)
		)
		(property "Author" "Antmicro"
			(at 212.59 -88.638 0)
			(layer "F.Fab")
			(hide yes)
			(effects
				(font
					(size 1 1)
					(thickness 0.15)
				)
			)
		)
		(property "License" "Apache-2.0"
			(at 212.59 -88.638 0)
			(layer "F.Fab")
			(hide yes)
			(effects
				(font
					(size 1 1)
					(thickness 0.15)
				)
			)
		)
		(property "MPN" "CR0402-FX-5101GLF"
			(at 212.59 -88.638 0)
			(layer "F.Fab")
			(hide yes)
			(effects
				(font
					(size 1 1)
					(thickness 0.15)
				)
			)
		)
		(property "Manufacturer" "Bourns"
			(at 212.59 -88.638 0)
			(layer "F.Fab")
			(hide yes)
			(effects
				(font
					(size 1 1)
					(thickness 0.15)
				)
			)
		)
		(property "Tolerance" "1%"
			(at 212.59 -88.638 0)
			(layer "F.Fab")
			(hide yes)
			(effects
				(font
					(size 1 1)
					(thickness 0.15)
				)
			)
		)
		(property "Val" "5k1"
			(at 212.59 -88.638 0)
			(layer "F.Fab")
			(hide yes)
			(effects
				(font
					(size 1 1)
					(thickness 0.15)
				)
			)
		)
		(sheetname "/Power/")
		(sheetfile "power.kicad_sch")
		(attr smd)
		(fp_rect
			(start -0.925 -0.47)
			(end 0.925 0.47)
			(stroke
				(width 0.05)
				(type default)
			)
			(fill no)
			(layer "F.CrtYd")
		)
		(fp_rect
			(start -0.5 -0.25)
			(end 0.5 0.25)
			(stroke
				(width 0.15)
				(type solid)
			)
			(fill no)
			(layer "F.Fab")
		)
		(pad "1" smd roundrect
			(at -0.48 0 90)
			(size 0.59 0.64)
			(layers "F.Cu" "F.Mask" "F.Paste")
			(roundrect_rratio 0.25)
			(net 4 "+12V")
			(pintype "passive")
		)
		(pad "2" smd roundrect
			(at 0.48 0 90)
			(size 0.59 0.64)
			(layers "F.Cu" "F.Mask" "F.Paste")
			(roundrect_rratio 0.25)
			(net 53 "Net-(L3-Pad2)")
			(pintype "passive")
		)
	)
	(footprint "antmicro-footprints:R_0402_1005Metric"
		(layer "F.Cu")
		(at 184.079 50.7008 -90)
		(descr "Resistor SMD 0402")
		(tags "resistor SMD 0402")
		(property "Reference" "R39"
			(at -1.016 0.763 90)
			(layer "F.SilkS")
			(effects
				(font
					(size 0.7 0.7)
					(thickness 0.15)
				)
				(justify right bottom)
			)
		)
		(property "Value" "R_10k_0402"
			(at -1.011843 1.772047 90)
			(layer "F.Fab")
			(effects
				(font
					(size 0.7 0.7)
					(thickness 0.15)
				)
				(justify right bottom)
			)
		)
		(property "Datasheet" "https://www.bourns.com/docs/product-datasheets/cr.pdf"
			(at 0 0 270)
			(layer "F.Fab")
			(hide yes)
			(effects
				(font
					(size 1.27 1.27)
					(thickness 0.15)
				)
			)
		)
		(property "Description" "SMD Chip Resistor, 10 kohm, ± 1%, 62.5 mW, 0402 [1005 Metric], Thick Film, General Purpose"
			(at 0 0 270)
			(layer "F.Fab")
			(hide yes)
			(effects
				(font
					(size 1.27 1.27)
					(thickness 0.15)
				)
			)
		)
		(property "Author" "Antmicro"
			(at 133.3782 234.7798 0)
			(layer "F.Fab")
			(hide yes)
			(effects
				(font
					(size 1 1)
					(thickness 0.15)
				)
			)
		)
		(property "License" "Apache-2.0"
			(at 133.3782 234.7798 0)
			(layer "F.Fab")
			(hide yes)
			(effects
				(font
					(size 1 1)
					(thickness 0.15)
				)
			)
		)
		(property "MPN" "CR0402-FX-1002GLF"
			(at 133.3782 234.7798 0)
			(layer "F.Fab")
			(hide yes)
			(effects
				(font
					(size 1 1)
					(thickness 0.15)
				)
			)
		)
		(property "Manufacturer" "Bourns"
			(at 133.3782 234.7798 0)
			(layer "F.Fab")
			(hide yes)
			(effects
				(font
					(size 1 1)
					(thickness 0.15)
				)
			)
		)
		(property "Tolerance" "1%"
			(at 133.3782 234.7798 0)
			(layer "F.Fab")
			(hide yes)
			(effects
				(font
					(size 1 1)
					(thickness 0.15)
				)
			)
		)
		(property "Val" "10k"
			(at 133.3782 234.7798 0)
			(layer "F.Fab")
			(hide yes)
			(effects
				(font
					(size 1 1)
					(thickness 0.15)
				)
			)
		)
		(sheetname "/Power/")
		(sheetfile "power.kicad_sch")
		(attr smd)
		(fp_rect
			(start -0.925 -0.47)
			(end 0.925 0.47)
			(stroke
				(width 0.05)
				(type default)
			)
			(fill no)
			(layer "F.CrtYd")
		)
		(fp_rect
			(start -0.5 -0.25)
			(end 0.5 0.25)
			(stroke
				(width 0.15)
				(type solid)
			)
			(fill no)
			(layer "F.Fab")
		)
		(pad "1" smd roundrect
			(at -0.48 0 270)
			(size 0.59 0.64)
			(layers "F.Cu" "F.Mask" "F.Paste")
			(roundrect_rratio 0.25)
			(net 72 "/Power/FFC_5V_FLG")
			(pintype "passive")
		)
		(pad "2" smd roundrect
			(at 0.48 0 270)
			(size 0.59 0.64)
			(layers "F.Cu" "F.Mask" "F.Paste")
			(roundrect_rratio 0.25)
			(net 3 "+1V8")
			(pintype "passive")
		)
	)
)
